# S9S_MB_2U (Grand Teton) — schematic netlist excerpt (pin names and nets, part order shuffled) for the footprints in the layout excerpt that follows; sources: Cadence DE-HDL packaged netlist, KiCad conversion of 03242023_DA0F0TMBIJ0_F0T_Motherboard_J_brd_V01_OCP.brd

J28  SCONN288_ADR50017P087CC  SCONN288_ADR50017-P087CC IO  pkg DDR288S_1-1VXB  page 109
  VIN_BULK0  = P12V_S3_AUX_CPU1_NVDIMM
  RFU0  = TP_CHF_CPU1_DIMM2_FRU_0
  VIN_MGMT  = P3V3_AUX
  HSCL  = I3C_SPD_DDREFGH_CPU1_LVC1_SCL_3
  HSDA  = I3C_SPD_DDREFGH_CPU1_LVC1_SDA
  VSS0  = GND
  DQ0_A  = M_F_CPU1_SA_DQ<0>
  VSS1  = GND
  DQ1_A  = M_F_CPU1_SA_DQ<1>
  VSS2  = GND
  DQS0_A_T  = M_F_CPU1_SA_DQS_DP<0>
  DQS0_A_C  = M_F_CPU1_SA_DQS_DN<0>
  VSS3  = GND
  DQ4_A  = M_F_CPU1_SA_DQ<4>
  VSS4  = GND
  DQ5_A  = M_F_CPU1_SA_DQ<5>
  VSS5  = GND
  DQ8_A  = M_F_CPU1_SA_DQ<8>
  VSS6  = GND
  DQ9_A  = M_F_CPU1_SA_DQ<9>
  VSS7  = GND
  DQS1_A_T  = M_F_CPU1_SA_DQS_DP<1>
  DQS1_A_C  = M_F_CPU1_SA_DQS_DN<1>
  VSS8  = GND
  DQ12_A  = M_F_CPU1_SA_DQ<12>
  VSS9  = GND
  DQ13_A  = M_F_CPU1_SA_DQ<13>
  VSS10  = GND
  DQ16_A  = M_F_CPU1_SA_DQ<16>
  VSS11  = GND
  DQ17_A  = M_F_CPU1_SA_DQ<17>
  VSS12  = GND
  DQS2_A_T  = M_F_CPU1_SA_DQS_DP<2>
  DQS2_A_C  = M_F_CPU1_SA_DQS_DN<2>
  VSS13  = GND
  DQ20_A  = M_F_CPU1_SA_DQ<20>
  VSS14  = GND
  DQ21_A  = M_F_CPU1_SA_DQ<21>
  VSS15  = GND
  DQ24_A  = M_F_CPU1_SA_DQ<24>
  VSS16  = GND
  DQ25_A  = M_F_CPU1_SA_DQ<25>
  VSS17  = GND
  DQS3_A_T  = M_F_CPU1_SA_DQS_DP<3>
  DQS3_A_C  = M_F_CPU1_SA_DQS_DN<3>
  VSS18  = GND
  DQ28_A  = M_F_CPU1_SA_DQ<28>
  VSS19  = GND
  DQ29_A  = M_F_CPU1_SA_DQ<29>
  VSS20  = GND
  CB0_A  = M_F_CPU1_SA_CB<0>
  VSS21  = GND
  CB1_A  = M_F_CPU1_SA_CB<1>
  VSS22  = GND
  DQS4_A_T  = M_F_CPU1_SA_DQS_DP<4>
  DQS4_A_C  = M_F_CPU1_SA_DQS_DN<4>
  VSS23  = GND
  CB4_A  = M_F_CPU1_SA_CB<4>
  VSS24  = GND
  CB5_A  = M_F_CPU1_SA_CB<5>
  VSS25  = GND
  ALERT_N  = M_F_CPU1_ALERT_N
  VSS26  = GND
  CS0_A_N  = M_F_CPU1_SA_CS_N<2>
  VSS27  = GND
  CA0_A  = M_F_CPU1_SA_CA<0>
  VSS28  = GND
  CA2_A  = M_F_CPU1_SA_CA<2>
  VSS29  = GND
  CA4_A  = M_F_CPU1_SA_CA<4>
  VSS30  = GND
  CA6_A  = M_F_CPU1_SA_CA<6>
  VSS31  = GND
  PAR_A  = M_F_CPU1_SA_PAR
  VSS32  = GND
  CA0_B  = M_F_CPU1_SB_CA<0>
  VSS33  = GND
  CA2_B  = M_F_CPU1_SB_CA<2>
  VSS34  = GND
  CA4_B  = M_F_CPU1_SB_CA<4>
  VSS35  = GND
  CA6_B  = M_F_CPU1_SB_CA<6>
  VSS36  = GND
  CS0_B_N  = M_F_CPU1_SB_CS_N<2>
  VSS37  = GND
  \lbd||rsp_a_n\  = M_F_CPU1_SA_RSP<1>
  \lbs||rsp_b_n\  = M_F_CPU1_SB_RSP<1>
  VSS38  = GND
  CB4_B  = M_F_CPU1_SB_CB<4>
  VSS39  = GND
  CB5_B  = M_F_CPU1_SB_CB<5>
  VSS40  = GND
  \dqs9_b_t||tdqs9_b_t||dbi4_b_n\  = M_F_CPU1_SB_DQS_DP<9>
  \dqs9_b_c||tdqs9_b_c\  = M_F_CPU1_SB_DQS_DN<9>
  VSS41  = GND
  CB0_B  = M_F_CPU1_SB_CB<0>
  VSS42  = GND
  CB1_B  = M_F_CPU1_SB_CB<1>
  VSS43  = GND
  DQ0_B  = M_F_CPU1_SB_DQ<0>
  VSS44  = GND
  DQ1_B  = M_F_CPU1_SB_DQ<1>
  VSS45  = GND
  DQS0_B_T  = M_F_CPU1_SB_DQS_DP<0>
  DQS0_B_C  = M_F_CPU1_SB_DQS_DN<0>
  VSS46  = GND
  DQ4_B  = M_F_CPU1_SB_DQ<4>
  VSS47  = GND
  DQ5_B  = M_F_CPU1_SB_DQ<5>
  VSS48  = GND
  DQ8_B  = M_F_CPU1_SB_DQ<8>
  VSS49  = GND
  DQ9_B  = M_F_CPU1_SB_DQ<9>
  VSS50  = GND
  DQS1_B_T  = M_F_CPU1_SB_DQS_DP<1>
  DQS1_B_C  = M_F_CPU1_SB_DQS_DN<1>
  VSS51  = GND
  DQ12_B  = M_F_CPU1_SB_DQ<12>
  VSS52  = GND
  DQ13_B  = M_F_CPU1_SB_DQ<13>
  VSS53  = GND
  DQ16_B  = M_F_CPU1_SB_DQ<16>
  VSS54  = GND
  DQ17_B  = M_F_CPU1_SB_DQ<17>
  VSS55  = GND
  DQS2_B_T  = M_F_CPU1_SB_DQS_DP<2>
  DQS2_B_C  = M_F_CPU1_SB_DQS_DN<2>
  VSS56  = GND
  DQ20_B  = M_F_CPU1_SB_DQ<20>
  VSS57  = GND
  DQ21_B  = M_F_CPU1_SB_DQ<21>
  VSS58  = GND
  DQ24_B  = M_F_CPU1_SB_DQ<24>
  VSS59  = GND
  DQ25_B  = M_F_CPU1_SB_DQ<25>
  VSS60  = GND
  DQS3_B_T  = M_F_CPU1_SB_DQS_DP<3>
  DQS3_B_C  = M_F_CPU1_SB_DQS_DN<3>
  VSS61  = GND
  DQ28_B  = M_F_CPU1_SB_DQ<28>
  VSS62  = GND
  DQ29_B  = M_F_CPU1_SB_DQ<29>
  VSS63  = GND
  RFU1  = TP_CHF_CPU1_DIMM2_FRU_1
  VIN_BULK1  = P12V_S3_AUX_CPU1_NVDIMM
  VIN_BULK2  = P12V_S3_AUX_CPU1_NVDIMM
  \pwr_good||fail_n\  = PWRGD_CHF_CPU1_DIMM2
  HSA  = PD_CHF_CPU1_DIMM2_SAA
  RFU2  = TP_CHF_CPU1_DIMM2_FRU_2
  RFU3  = TP_CHF_CPU1_DIMM2_FRU_3
  VSS64  = GND
  DQ2_A  = M_F_CPU1_SA_DQ<2>
  VSS65  = GND
  DQ3_A  = M_F_CPU1_SA_DQ<3>
  VSS66  = GND
  \dqs5_a_c||tdqs5_a_c||dqs5_a_t||tdqs5_a_t\  = M_F_CPU1_SA_DQS_DN<5>
  \dqs5_a_t||tdqs5_a_t\  = M_F_CPU1_SA_DQS_DP<5>
  VSS67  = GND
  DQ6_A  = M_F_CPU1_SA_DQ<6>
  VSS68  = GND
  DQ7_A  = M_F_CPU1_SA_DQ<7>
  VSS69  = GND
  DQ10_A  = M_F_CPU1_SA_DQ<10>
  VSS70  = GND
  DQ11_A  = M_F_CPU1_SA_DQ<11>
  VSS71  = GND
  \dqs6_a_c||tdqs6_a_c||dqs6_a_t||tdqs6_a_t\  = M_F_CPU1_SA_DQS_DN<6>
  \dqs6_a_t||tdqs6_a_t\  = M_F_CPU1_SA_DQS_DP<6>
  VSS72  = GND
  DQ14_A  = M_F_CPU1_SA_DQ<14>
  VSS73  = GND
  DQ15_A  = M_F_CPU1_SA_DQ<15>
  VSS74  = GND
  DQ18_A  = M_F_CPU1_SA_DQ<18>
  VSS75  = GND
  DQ19_A  = M_F_CPU1_SA_DQ<19>
  VSS76  = GND
  \dqs7_a_c||tdqs7_a_c\  = M_F_CPU1_SA_DQS_DN<7>
  \dqs7_a_t||tdqs7_a_t\  = M_F_CPU1_SA_DQS_DP<7>
  VSS77  = GND
  DQ22_A  = M_F_CPU1_SA_DQ<22>
  VSS78  = GND
  DQ23_A  = M_F_CPU1_SA_DQ<23>
  VSS79  = GND
  DQ26_A  = M_F_CPU1_SA_DQ<26>
  VSS80  = GND
  DQ27_A  = M_F_CPU1_SA_DQ<27>
  VSS81  = GND
  \dqs8_a_c||tdqs8_a_c\  = M_F_CPU1_SA_DQS_DN<8>
  \dqs8_a_t||tdqs8_a_t\  = M_F_CPU1_SA_DQS_DP<8>
  VSS82  = GND
  DQ30_A  = M_F_CPU1_SA_DQ<30>
  VSS83  = GND
  DQ31_A  = M_F_CPU1_SA_DQ<31>
  VSS84  = GND
  CB2_A  = M_F_CPU1_SA_CB<2>
  VSS85  = GND
  CB3_A  = M_F_CPU1_SA_CB<3>
  VSS86  = GND
  \dqs9_a_c||tdqs9_a_c\  = M_F_CPU1_SA_DQS_DN<9>
  \dqs9_a_t||tdqs9_a_t\  = M_F_CPU1_SA_DQS_DP<9>
  VSS87  = GND
  CB6_A  = M_F_CPU1_SA_CB<6>
  VSS88  = GND
  CB7_A  = M_F_CPU1_SA_CB<7>
  VSS89  = GND
  RESET_N  = RST_M_EF_CPU1_FPGA_N
  VSS90  = GND
  CS1_A_N  = M_F_CPU1_SA_CS_N<3>
  VSS91  = GND
  CA1_A  = M_F_CPU1_SA_CA<1>
  VSS92  = GND
  CA3_A  = M_F_CPU1_SA_CA<3>
  VSS93  = GND
  CA5_A  = M_F_CPU1_SA_CA<5>
  VSS94  = GND
  CK_T  = M_F_CPU1_CLK_DP<1>
  CK_C  = M_F_CPU1_CLK_DN<1>
  VSS95  = GND
  RFU4  = TP_CHF_CPU1_DIMM2_FRU_4
  CA1_B  = M_F_CPU1_SB_CA<1>
  VSS96  = GND
  CA3_B  = M_F_CPU1_SB_CA<3>
  VSS97  = GND
  CA5_B  = M_F_CPU1_SB_CA<5>
  VSS98  = GND
  PAR_B  = M_F_CPU1_SB_PAR
  VSS99  = GND
  CS1_B_N  = M_F_CPU1_SB_CS_N<3>
  VSS100  = GND
  RFU5  = TP_CHF_CPU1_DIMM2_FRU_5
  RFU6  = TP_CHF_CPU1_DIMM2_FRU_6
  VSS101  = GND
  CB6_B  = M_F_CPU1_SB_CB<6>
  VSS102  = GND
  CB7_B  = M_F_CPU1_SB_CB<7>
  VSS103  = GND
  DQS4_B_C  = M_F_CPU1_SB_DQS_DN<4>
  DQS4_B_T  = M_F_CPU1_SB_DQS_DP<4>
  VSS104  = GND
  CB2_B  = M_F_CPU1_SB_CB<2>
  VSS105  = GND
  CB3_B  = M_F_CPU1_SB_CB<3>
  VSS106  = GND
  DQ2_B  = M_F_CPU1_SB_DQ<2>
  VSS107  = GND
  DQ3_B  = M_F_CPU1_SB_DQ<3>
  VSS108  = GND
  \dqs5_b_c||tdqs5_b_c\  = M_F_CPU1_SB_DQS_DN<5>
  \dqs5_b_t||tdqs5_b_t\  = M_F_CPU1_SB_DQS_DP<5>
  VSS109  = GND
  DQ6_B  = M_F_CPU1_SB_DQ<6>
  VSS110  = GND
  DQ7_B  = M_F_CPU1_SB_DQ<7>
  VSS111  = GND
  DQ10_B  = M_F_CPU1_SB_DQ<10>
  VSS112  = GND
  DQ11_B  = M_F_CPU1_SB_DQ<11>
  VSS113  = GND
  \dqs6_b_c||tdqs6_b_c\  = M_F_CPU1_SB_DQS_DN<6>
  \dqs6_b_t||tdqs6_b_t\  = M_F_CPU1_SB_DQS_DP<6>
  VSS114  = GND
  DQ14_B  = M_F_CPU1_SB_DQ<14>
  VSS115  = GND
  DQ15_B  = M_F_CPU1_SB_DQ<15>
  VSS116  = GND
  DQ18_B  = M_F_CPU1_SB_DQ<18>
  VSS117  = GND
  DQ19_B  = M_F_CPU1_SB_DQ<19>
  VSS118  = GND
  \dqs7_b_c||tdqs7_b_c\  = M_F_CPU1_SB_DQS_DN<7>
  \dqs7_b_t||tdqs7_b_t\  = M_F_CPU1_SB_DQS_DP<7>
  VSS119  = GND
  DQ22_B  = M_F_CPU1_SB_DQ<22>
  VSS120  = GND
  DQ23_B  = M_F_CPU1_SB_DQ<23>
  VSS121  = GND
  DQ26_B  = M_F_CPU1_SB_DQ<26>
  VSS122  = GND
  DQ27_B  = M_F_CPU1_SB_DQ<27>
  VSS123  = GND
  \dqs8_b_c||tdqs8_b_c\  = M_F_CPU1_SB_DQS_DN<8>
  \dqs8_b_t||tdqs8_b_t\  = M_F_CPU1_SB_DQS_DP<8>
  VSS124  = GND
  DQ30_B  = M_F_CPU1_SB_DQ<30>
  VSS125  = GND
  DQ31_B  = M_F_CPU1_SB_DQ<31>
  VSS126  = GND
  G1  = GND
  G2  = GND
  G3  = GND

(kicad_pcb
	(version 20260206)
	(generator "pcbnew")
	(generator_version "10.0")
	(general
		(thickness 1.6)
		(legacy_teardrops no)
	)
	(paper "A4")
	(title_block
		(title "03242023_DA0F0TMBIJ0_F0T_Motherboard_J_brd_V01_OCP.brd")
		(comment 1 "Grand Teton / footprint 3431 of 6105 (J28), pads 183-228 of 291")
	)
	(layers
		(0 "F.Cu" signal "TOP")
		(4 "In1.Cu" signal "GND")
		(6 "In2.Cu" signal "IN1")
		(8 "In3.Cu" signal "GND1")
		(10 "In4.Cu" signal "IN2")
		(12 "In5.Cu" signal "GND2")
		(14 "In6.Cu" signal "IN3")
		(16 "In7.Cu" signal "GND3")
		(18 "In8.Cu" signal "VCC")
		(20 "In9.Cu" signal "VCC1")
		(22 "In10.Cu" signal "GND4")
		(24 "In11.Cu" signal "IN4")
		(26 "In12.Cu" signal "GND5")
		(28 "In13.Cu" signal "IN5")
		(30 "In14.Cu" signal "GND6")
		(32 "In15.Cu" signal "IN6")
		(34 "In16.Cu" signal "GND7")
		(2 "B.Cu" signal "BOTTOM")
		(9 "F.Adhes" user "F.Adhesive")
		(11 "B.Adhes" user "B.Adhesive")
		(13 "F.Paste" user "Package Geometry/Pastemask Top")
		(15 "B.Paste" user "Package Geometry/Pastemask Bottom")
		(5 "F.SilkS" user "Ref Des/Silkscreen Top")
		(7 "B.SilkS" user "Ref Des/Silkscreen Bottom")
		(1 "F.Mask" user "Board Geometry/Soldermask Top")
		(3 "B.Mask" user "Board Geometry/Soldermask Bottom")
		(17 "Dwgs.User" user "User.Drawings")
		(19 "Cmts.User" user "User.Comments")
		(21 "Eco1.User" user "User.Eco1")
		(23 "Eco2.User" user "User.Eco2")
		(25 "Edge.Cuts" user "Board Geometry/Outline")
		(27 "Margin" user)
		(31 "F.CrtYd" user "Package Geometry/Place Bound Top")
		(29 "B.CrtYd" user "Package Geometry/Place Bound Bottom")
		(35 "F.Fab" user "Ref Des/Assembly Top")
		(33 "B.Fab" user "Ref Des/Assembly Bottom")
	)
	(footprint ""
		(layer "F.Cu")
		(at 175.95088 -258.091686)
		(property "Reference" "J28"
			(at -0.26924 -81.680812 0)
			(unlocked yes)
			(layer "F.SilkS")
			(effects
				(font
					(size 0.7874 0.5842)
					(thickness 0.1524)
				)
				(justify left)
			)
		)
		(property "Value" ""
			(at 0 0 0)
			(layer "F.Fab")
			(effects
				(font
					(size 1.27 1.27)
				)
			)
		)
		(duplicate_pad_numbers_are_jumpers no)
		(pad "183" smd rect
			(at 2.050034 -31.025084 270)
			(size 0.519938 1.4986)
			(layers "F.Cu" "F.Mask" "F.Paste")
			(net "M_F_CPU1_SA_DQ<23>")
		)
		(pad "184" smd rect
			(at 2.050034 -30.174946 270)
			(size 0.519938 1.4986)
			(layers "F.Cu" "F.Mask" "F.Paste")
			(net "GND")
		)
		(pad "185" smd rect
			(at 2.050034 -29.325062 270)
			(size 0.519938 1.4986)
			(layers "F.Cu" "F.Mask" "F.Paste")
			(net "M_F_CPU1_SA_DQ<26>")
		)
		(pad "186" smd rect
			(at 2.050034 -28.474924 270)
			(size 0.519938 1.4986)
			(layers "F.Cu" "F.Mask" "F.Paste")
			(net "GND")
		)
		(pad "187" smd rect
			(at 2.050034 -27.62504 270)
			(size 0.519938 1.4986)
			(layers "F.Cu" "F.Mask" "F.Paste")
			(net "M_F_CPU1_SA_DQ<27>")
		)
		(pad "188" smd rect
			(at 2.050034 -26.774902 270)
			(size 0.519938 1.4986)
			(layers "F.Cu" "F.Mask" "F.Paste")
			(net "GND")
		)
		(pad "189" smd rect
			(at 2.050034 -25.925018 270)
			(size 0.519938 1.4986)
			(layers "F.Cu" "F.Mask" "F.Paste")
			(net "M_F_CPU1_SA_DQS_DN<8>")
		)
		(pad "190" smd rect
			(at 2.050034 -25.07488 270)
			(size 0.519938 1.4986)
			(layers "F.Cu" "F.Mask" "F.Paste")
			(net "M_F_CPU1_SA_DQS_DP<8>")
		)
		(pad "191" smd rect
			(at 2.050034 -24.224996 270)
			(size 0.519938 1.4986)
			(layers "F.Cu" "F.Mask" "F.Paste")
			(net "GND")
		)
		(pad "192" smd rect
			(at 2.050034 -23.375112 270)
			(size 0.519938 1.4986)
			(layers "F.Cu" "F.Mask" "F.Paste")
			(net "M_F_CPU1_SA_DQ<30>")
		)
		(pad "193" smd rect
			(at 2.050034 -22.524974 270)
			(size 0.519938 1.4986)
			(layers "F.Cu" "F.Mask" "F.Paste")
			(net "GND")
		)
		(pad "194" smd rect
			(at 2.050034 -21.67509 270)
			(size 0.519938 1.4986)
			(layers "F.Cu" "F.Mask" "F.Paste")
			(net "M_F_CPU1_SA_DQ<31>")
		)
		(pad "195" smd rect
			(at 2.050034 -20.824952 270)
			(size 0.519938 1.4986)
			(layers "F.Cu" "F.Mask" "F.Paste")
			(net "GND")
		)
		(pad "196" smd rect
			(at 2.050034 -19.975068 270)
			(size 0.519938 1.4986)
			(layers "F.Cu" "F.Mask" "F.Paste")
			(net "M_F_CPU1_SA_CB<2>")
		)
		(pad "197" smd rect
			(at 2.050034 -19.12493 270)
			(size 0.519938 1.4986)
			(layers "F.Cu" "F.Mask" "F.Paste")
			(net "GND")
		)
		(pad "198" smd rect
			(at 2.050034 -18.275046 270)
			(size 0.519938 1.4986)
			(layers "F.Cu" "F.Mask" "F.Paste")
			(net "M_F_CPU1_SA_CB<3>")
		)
		(pad "199" smd rect
			(at 2.050034 -17.424908 270)
			(size 0.519938 1.4986)
			(layers "F.Cu" "F.Mask" "F.Paste")
			(net "GND")
		)
		(pad "200" smd rect
			(at 2.050034 -16.575024 270)
			(size 0.519938 1.4986)
			(layers "F.Cu" "F.Mask" "F.Paste")
			(net "M_F_CPU1_SA_DQS_DN<9>")
		)
		(pad "201" smd rect
			(at 2.050034 -15.724886 270)
			(size 0.519938 1.4986)
			(layers "F.Cu" "F.Mask" "F.Paste")
			(net "M_F_CPU1_SA_DQS_DP<9>")
		)
		(pad "202" smd rect
			(at 2.050034 -14.875002 270)
			(size 0.519938 1.4986)
			(layers "F.Cu" "F.Mask" "F.Paste")
			(net "GND")
		)
		(pad "203" smd rect
			(at 2.050034 -14.025118 270)
			(size 0.519938 1.4986)
			(layers "F.Cu" "F.Mask" "F.Paste")
			(net "M_F_CPU1_SA_CB<6>")
		)
		(pad "204" smd rect
			(at 2.050034 -13.17498 270)
			(size 0.519938 1.4986)
			(layers "F.Cu" "F.Mask" "F.Paste")
			(net "GND")
		)
		(pad "205" smd rect
			(at 2.050034 -12.325096 270)
			(size 0.519938 1.4986)
			(layers "F.Cu" "F.Mask" "F.Paste")
			(net "M_F_CPU1_SA_CB<7>")
		)
		(pad "206" smd rect
			(at 2.050034 -11.474958 270)
			(size 0.519938 1.4986)
			(layers "F.Cu" "F.Mask" "F.Paste")
			(net "GND")
		)
		(pad "207" smd rect
			(at 2.050034 -10.625074 270)
			(size 0.519938 1.4986)
			(layers "F.Cu" "F.Mask" "F.Paste")
			(net "RST_M_EF_CPU1_FPGA_N")
		)
		(pad "208" smd rect
			(at 2.050034 -9.774936 270)
			(size 0.519938 1.4986)
			(layers "F.Cu" "F.Mask" "F.Paste")
			(net "GND")
		)
		(pad "209" smd rect
			(at 2.050034 -8.925052 270)
			(size 0.519938 1.4986)
			(layers "F.Cu" "F.Mask" "F.Paste")
			(net "M_F_CPU1_SA_CS_N<3>")
		)
		(pad "210" smd rect
			(at 2.050034 -8.074914 270)
			(size 0.519938 1.4986)
			(layers "F.Cu" "F.Mask" "F.Paste")
			(net "GND")
		)
		(pad "211" smd rect
			(at 2.050034 -7.22503 270)
			(size 0.519938 1.4986)
			(layers "F.Cu" "F.Mask" "F.Paste")
			(net "M_F_CPU1_SA_CA<1>")
		)
		(pad "212" smd rect
			(at 2.050034 -6.374892 270)
			(size 0.519938 1.4986)
			(layers "F.Cu" "F.Mask" "F.Paste")
			(net "GND")
		)
		(pad "213" smd rect
			(at 2.050034 -5.525008 270)
			(size 0.519938 1.4986)
			(layers "F.Cu" "F.Mask" "F.Paste")
			(net "M_F_CPU1_SA_CA<3>")
		)
		(pad "214" smd rect
			(at 2.050034 -4.675124 270)
			(size 0.519938 1.4986)
			(layers "F.Cu" "F.Mask" "F.Paste")
			(net "GND")
		)
		(pad "215" smd rect
			(at 2.050034 -3.824986 270)
			(size 0.519938 1.4986)
			(layers "F.Cu" "F.Mask" "F.Paste")
			(net "M_F_CPU1_SA_CA<5>")
		)
		(pad "216" smd rect
			(at 2.050034 -2.975102 270)
			(size 0.519938 1.4986)
			(layers "F.Cu" "F.Mask" "F.Paste")
			(net "GND")
		)
		(pad "217" smd rect
			(at 2.050034 -2.124964 270)
			(size 0.519938 1.4986)
			(layers "F.Cu" "F.Mask" "F.Paste")
			(net "M_F_CPU1_CLK_DP<1>")
		)
		(pad "218" smd rect
			(at 2.050034 -1.27508 270)
			(size 0.519938 1.4986)
			(layers "F.Cu" "F.Mask" "F.Paste")
			(net "M_F_CPU1_CLK_DN<1>")
		)
		(pad "219" smd rect
			(at 2.050034 -0.424942 270)
			(size 0.519938 1.4986)
			(layers "F.Cu" "F.Mask" "F.Paste")
			(net "GND")
		)
		(pad "220" smd rect
			(at 2.050034 5.525008 270)
			(size 0.519938 1.4986)
			(layers "F.Cu" "F.Mask" "F.Paste")
			(net "TP_CHF_CPU1_DIMM2_FRU_4")
		)
		(pad "221" smd rect
			(at 2.050034 6.374892 270)
			(size 0.519938 1.4986)
			(layers "F.Cu" "F.Mask" "F.Paste")
			(net "M_F_CPU1_SB_CA<1>")
		)
		(pad "222" smd rect
			(at 2.050034 7.22503 270)
			(size 0.519938 1.4986)
			(layers "F.Cu" "F.Mask" "F.Paste")
			(net "GND")
		)
		(pad "223" smd rect
			(at 2.050034 8.074914 270)
			(size 0.519938 1.4986)
			(layers "F.Cu" "F.Mask" "F.Paste")
			(net "M_F_CPU1_SB_CA<3>")
		)
		(pad "224" smd rect
			(at 2.050034 8.925052 270)
			(size 0.519938 1.4986)
			(layers "F.Cu" "F.Mask" "F.Paste")
			(net "GND")
		)
		(pad "225" smd rect
			(at 2.050034 9.774936 270)
			(size 0.519938 1.4986)
			(layers "F.Cu" "F.Mask" "F.Paste")
			(net "M_F_CPU1_SB_CA<5>")
		)
		(pad "226" smd rect
			(at 2.050034 10.625074 270)
			(size 0.519938 1.4986)
			(layers "F.Cu" "F.Mask" "F.Paste")
			(net "GND")
		)
		(pad "227" smd rect
			(at 2.050034 11.474958 270)
			(size 0.519938 1.4986)
			(layers "F.Cu" "F.Mask" "F.Paste")
			(net "M_F_CPU1_SB_PAR")
		)
		(pad "228" smd rect
			(at 2.050034 12.325096 270)
			(size 0.519938 1.4986)
			(layers "F.Cu" "F.Mask" "F.Paste")
			(net "GND")
		)
	)
)
